FILE_TYPE = CONNECTIVITY;
{Allegro Design Entry HDL 17.2-2016 S081 (4005846) 1/11/2022}
"PAGE_NUMBER" = 8;
0"NC";
END.
